(kicad_pcb
	(version 20260206)
	(generator "pcbnew")
	(generator_version "10.0")
	(general
		(thickness 1.6)
		(legacy_teardrops no)
	)
	(paper "A4")
	(title_block
		(title "fcb — Lightning_FCB_BRD.brd")
		(comment 1 "Lightning (Wiwynn / Facebook NVMe JBOF) / footprints 448-454 of 495")
	)
	(layers
		(0 "F.Cu" signal "TOP")
		(4 "In1.Cu" signal "L2GND")
		(6 "In2.Cu" signal "L3VCC")
		(2 "B.Cu" signal "BOTTOM")
		(9 "F.Adhes" user "F.Adhesive")
		(11 "B.Adhes" user "B.Adhesive")
		(13 "F.Paste" user "Package Geometry/Pastemask Top")
		(15 "B.Paste" user "Package Geometry/Pastemask Bottom")
		(5 "F.SilkS" user "Ref Des/Silkscreen Top")
		(7 "B.SilkS" user "Ref Des/Silkscreen Bottom")
		(1 "F.Mask" user "Board Geometry/Soldermask Top")
		(3 "B.Mask" user "Board Geometry/Soldermask Bottom")
		(17 "Dwgs.User" user "User.Drawings")
		(19 "Cmts.User" user "User.Comments")
		(21 "Eco1.User" user "User.Eco1")
		(23 "Eco2.User" user "User.Eco2")
		(25 "Edge.Cuts" user "Board Geometry/Outline")
		(27 "Margin" user)
		(31 "F.CrtYd" user "Package Geometry/Place Bound Top")
		(29 "B.CrtYd" user "Package Geometry/Place Bound Bottom")
		(35 "F.Fab" user "Ref Des/Assembly Top")
		(33 "B.Fab" user "Ref Des/Assembly Bottom")
	)
	(footprint ""
		(layer "F.Cu")
		(at 38.862 -240.665 180)
		(property "Reference" "R156"
			(at 0 0 180)
			(layer "F.SilkS")
			(hide yes)
			(effects
				(font
					(size 1.27 1.27)
				)
			)
		)
		(property "Value" "330R2J-3-GP"
			(at 0.064008 -3.993896 180)
			(unlocked yes)
			(layer "F.Fab")
			(hide yes)
			(effects
				(font
					(size 1.016 1.016)
					(thickness 0.1524)
				)
			)
		)
		(property "Device Type" "R402H16"
			(at 0.064008 -5.517896 180)
			(unlocked yes)
			(layer "F.Fab")
			(hide yes)
			(effects
				(font
					(size 1.016 1.016)
					(thickness 0.1524)
				)
			)
		)
		(duplicate_pad_numbers_are_jumpers no)
		(fp_line
			(start 0.508 -0.9398)
			(end -0.508 -0.9398)
			(stroke
				(width 0.1524)
				(type default)
			)
			(layer "F.SilkS")
		)
		(fp_line
			(start -0.508 -0.9398)
			(end -0.508 0.9398)
			(stroke
				(width 0.1524)
				(type default)
			)
			(layer "F.SilkS")
		)
		(fp_rect
			(start -0.508 0.9398)
			(end 0.508 -0.9398)
			(stroke
				(width 0)
				(type default)
			)
			(fill no)
			(layer "F.CrtYd")
		)
		(fp_rect
			(start -0.508 0.9398)
			(end 0.508 -0.9398)
			(stroke
				(width 0)
				(type default)
			)
			(fill no)
			(layer "F.Fab")
		)
		(pad "1" smd custom
			(at 0 -0.4445 180)
			(size 0.1397 0.1397)
			(layers "F.Cu" "F.Mask" "F.Paste")
			(net "P3V3")
			(options
				(clearance outline)
				(anchor circle)
			)
			(primitives
				(gr_poly
					(pts
						(arc
							(start -0.1778 -0.2794)
							(mid -0.249642 -0.249642)
							(end -0.2794 -0.1778)
						)
						(arc
							(start -0.2794 0.1778)
							(mid -0.249642 0.249642)
							(end -0.1778 0.2794)
						)
						(arc
							(start 0.1778 0.2794)
							(mid 0.249642 0.249642)
							(end 0.2794 0.1778)
						)
						(arc
							(start 0.2794 -0.1778)
							(mid 0.249642 -0.249642)
							(end 0.1778 -0.2794)
						)
					)
					(width 0)
					(fill yes)
				)
			)
		)
		(pad "2" smd custom
			(at 0 0.4445 180)
			(size 0.1397 0.1397)
			(layers "F.Cu" "F.Mask" "F.Paste")
			(net "LED_DR_LED2")
			(options
				(clearance outline)
				(anchor circle)
			)
			(primitives
				(gr_poly
					(pts
						(arc
							(start -0.1778 -0.2794)
							(mid -0.249642 -0.249642)
							(end -0.2794 -0.1778)
						)
						(arc
							(start -0.2794 0.1778)
							(mid -0.249642 0.249642)
							(end -0.1778 0.2794)
						)
						(arc
							(start 0.1778 0.2794)
							(mid 0.249642 0.249642)
							(end 0.2794 0.1778)
						)
						(arc
							(start 0.2794 -0.1778)
							(mid 0.249642 -0.249642)
							(end 0.1778 -0.2794)
						)
					)
					(width 0)
					(fill yes)
				)
			)
		)
	)
	(footprint ""
		(layer "F.Cu")
		(at 32.9946 -251.3838 180)
		(property "Reference" "C19"
			(at 0 0 180)
			(layer "F.SilkS")
			(hide yes)
			(effects
				(font
					(size 1.27 1.27)
				)
			)
		)
		(property "Value" "SC1U16V3KX-5GP"
			(at 0 -2.8194 180)
			(unlocked yes)
			(layer "F.Fab")
			(hide yes)
			(effects
				(font
					(size 1.016 1.016)
					(thickness 0.1524)
				)
			)
		)
		(property "Device Type" "C603H36"
			(at 0 -4.3434 180)
			(unlocked yes)
			(layer "F.Fab")
			(hide yes)
			(effects
				(font
					(size 1.016 1.016)
					(thickness 0.1524)
				)
			)
		)
		(duplicate_pad_numbers_are_jumpers no)
		(fp_line
			(start 0.508 0)
			(end -0.508 0)
			(stroke
				(width 0.2032)
				(type default)
			)
			(layer "F.SilkS")
		)
		(fp_rect
			(start -0.5842 1.3335)
			(end 0.5842 -1.3335)
			(stroke
				(width 0)
				(type default)
			)
			(fill no)
			(layer "F.CrtYd")
		)
		(fp_rect
			(start -0.5842 1.3335)
			(end 0.5842 -1.3335)
			(stroke
				(width 0)
				(type default)
			)
			(fill no)
			(layer "F.Fab")
		)
		(pad "1" smd custom
			(at 0 -0.762 180)
			(size 0.2159 0.2159)
			(layers "F.Cu" "F.Mask" "F.Paste")
			(net "P3V3")
			(options
				(clearance outline)
				(anchor circle)
			)
			(primitives
				(gr_poly
					(pts
						(arc
							(start -0.3302 -0.4318)
							(mid -0.402042 -0.402042)
							(end -0.4318 -0.3302)
						)
						(arc
							(start -0.4318 0.3302)
							(mid -0.402042 0.402042)
							(end -0.3302 0.4318)
						)
						(arc
							(start 0.3302 0.4318)
							(mid 0.402042 0.402042)
							(end 0.4318 0.3302)
						)
						(arc
							(start 0.4318 -0.3302)
							(mid 0.402042 -0.402042)
							(end 0.3302 -0.4318)
						)
					)
					(width 0)
					(fill yes)
				)
			)
		)
		(pad "2" smd custom
			(at 0 0.762 180)
			(size 0.2159 0.2159)
			(layers "F.Cu" "F.Mask" "F.Paste")
			(net "GND")
			(options
				(clearance outline)
				(anchor circle)
			)
			(primitives
				(gr_poly
					(pts
						(arc
							(start -0.3302 -0.4318)
							(mid -0.402042 -0.402042)
							(end -0.4318 -0.3302)
						)
						(arc
							(start -0.4318 0.3302)
							(mid -0.402042 0.402042)
							(end -0.3302 0.4318)
						)
						(arc
							(start 0.3302 0.4318)
							(mid 0.402042 0.402042)
							(end 0.4318 0.3302)
						)
						(arc
							(start 0.4318 -0.3302)
							(mid 0.402042 -0.402042)
							(end 0.3302 -0.4318)
						)
					)
					(width 0)
					(fill yes)
				)
			)
		)
	)
	(footprint ""
		(layer "F.Cu")
		(at 17.119092 -17.602962 180)
		(property "Reference" "R67"
			(at 0 0 180)
			(layer "F.SilkS")
			(hide yes)
			(effects
				(font
					(size 1.27 1.27)
				)
			)
		)
		(property "Value" "4K7R2F-GP"
			(at 0.064008 -3.993896 180)
			(unlocked yes)
			(layer "F.Fab")
			(hide yes)
			(effects
				(font
					(size 1.016 1.016)
					(thickness 0.1524)
				)
			)
		)
		(property "Device Type" "R402H16"
			(at 0.064008 -5.517896 180)
			(unlocked yes)
			(layer "F.Fab")
			(hide yes)
			(effects
				(font
					(size 1.016 1.016)
					(thickness 0.1524)
				)
			)
		)
		(duplicate_pad_numbers_are_jumpers no)
		(fp_line
			(start 0.508 -0.9398)
			(end -0.508 -0.9398)
			(stroke
				(width 0.1524)
				(type default)
			)
			(layer "F.SilkS")
		)
		(fp_line
			(start -0.508 -0.9398)
			(end -0.508 0.9398)
			(stroke
				(width 0.1524)
				(type default)
			)
			(layer "F.SilkS")
		)
		(fp_rect
			(start -0.508 0.9398)
			(end 0.508 -0.9398)
			(stroke
				(width 0)
				(type default)
			)
			(fill no)
			(layer "F.CrtYd")
		)
		(fp_rect
			(start -0.508 1.0668)
			(end 0.508 -0.8128)
			(stroke
				(width 0)
				(type default)
			)
			(fill no)
			(layer "F.Fab")
		)
		(pad "1" smd custom
			(at 0 -0.4445 180)
			(size 0.1397 0.1397)
			(layers "F.Cu" "F.Mask" "F.Paste")
			(net "P12V")
			(options
				(clearance outline)
				(anchor circle)
			)
			(primitives
				(gr_poly
					(pts
						(arc
							(start -0.1778 -0.2794)
							(mid -0.249642 -0.249642)
							(end -0.2794 -0.1778)
						)
						(arc
							(start -0.2794 0.1778)
							(mid -0.249642 0.249642)
							(end -0.1778 0.2794)
						)
						(arc
							(start 0.1778 0.2794)
							(mid 0.249642 0.249642)
							(end 0.2794 0.1778)
						)
						(arc
							(start 0.2794 -0.1778)
							(mid 0.249642 -0.249642)
							(end 0.1778 -0.2794)
						)
					)
					(width 0)
					(fill yes)
				)
			)
		)
		(pad "2" smd custom
			(at 0 0.4445 180)
			(size 0.1397 0.1397)
			(layers "F.Cu" "F.Mask" "F.Paste")
			(net "FAN_TACH12")
			(options
				(clearance outline)
				(anchor circle)
			)
			(primitives
				(gr_poly
					(pts
						(arc
							(start -0.1778 -0.2794)
							(mid -0.249642 -0.249642)
							(end -0.2794 -0.1778)
						)
						(arc
							(start -0.2794 0.1778)
							(mid -0.249642 0.249642)
							(end -0.1778 0.2794)
						)
						(arc
							(start 0.1778 0.2794)
							(mid 0.249642 0.249642)
							(end 0.2794 0.1778)
						)
						(arc
							(start 0.2794 -0.1778)
							(mid 0.249642 -0.249642)
							(end 0.1778 -0.2794)
						)
					)
					(width 0)
					(fill yes)
				)
			)
		)
	)
	(footprint ""
		(layer "F.Cu")
		(at 41.3766 -140.5382 -90)
		(property "Reference" "PC98"
			(at 0 0 270)
			(layer "F.SilkS")
			(hide yes)
			(effects
				(font
					(size 1.27 1.27)
				)
			)
		)
		(property "Value" "SCD1U50V3KX-GP"
			(at 0 -2.8194 270)
			(unlocked yes)
			(layer "F.Fab")
			(hide yes)
			(effects
				(font
					(size 1.016 1.016)
					(thickness 0.1524)
				)
			)
		)
		(property "Device Type" "C603H36"
			(at 0 -4.3434 270)
			(unlocked yes)
			(layer "F.Fab")
			(hide yes)
			(effects
				(font
					(size 1.016 1.016)
					(thickness 0.1524)
				)
			)
		)
		(duplicate_pad_numbers_are_jumpers no)
		(fp_line
			(start 0.508 0)
			(end -0.508 0)
			(stroke
				(width 0.2032)
				(type default)
			)
			(layer "F.SilkS")
		)
		(fp_rect
			(start -0.5842 1.3335)
			(end 0.5842 -1.3335)
			(stroke
				(width 0)
				(type default)
			)
			(fill no)
			(layer "F.CrtYd")
		)
		(fp_rect
			(start -0.5842 1.3335)
			(end 0.5842 -1.3335)
			(stroke
				(width 0)
				(type default)
			)
			(fill no)
			(layer "F.Fab")
		)
		(pad "1" smd custom
			(at 0 -0.762 270)
			(size 0.2159 0.2159)
			(layers "F.Cu" "F.Mask" "F.Paste")
			(net "P12VL_2490_EN_2")
			(options
				(clearance outline)
				(anchor circle)
			)
			(primitives
				(gr_poly
					(pts
						(arc
							(start -0.3302 -0.4318)
							(mid -0.402042 -0.402042)
							(end -0.4318 -0.3302)
						)
						(arc
							(start -0.4318 0.3302)
							(mid -0.402042 0.402042)
							(end -0.3302 0.4318)
						)
						(arc
							(start 0.3302 0.4318)
							(mid 0.402042 0.402042)
							(end 0.4318 0.3302)
						)
						(arc
							(start 0.4318 -0.3302)
							(mid 0.402042 -0.402042)
							(end 0.3302 -0.4318)
						)
					)
					(width 0)
					(fill yes)
				)
			)
		)
		(pad "2" smd custom
			(at 0 0.762 270)
			(size 0.2159 0.2159)
			(layers "F.Cu" "F.Mask" "F.Paste")
			(net "GND")
			(options
				(clearance outline)
				(anchor circle)
			)
			(primitives
				(gr_poly
					(pts
						(arc
							(start -0.3302 -0.4318)
							(mid -0.402042 -0.402042)
							(end -0.4318 -0.3302)
						)
						(arc
							(start -0.4318 0.3302)
							(mid -0.402042 0.402042)
							(end -0.3302 0.4318)
						)
						(arc
							(start 0.3302 0.4318)
							(mid 0.402042 0.402042)
							(end 0.4318 0.3302)
						)
						(arc
							(start 0.4318 -0.3302)
							(mid 0.402042 -0.402042)
							(end 0.3302 -0.4318)
						)
					)
					(width 0)
					(fill yes)
				)
			)
		)
	)
	(footprint ""
		(layer "F.Cu")
		(at 34.29 -358.166416)
		(property "Reference" "R364"
			(at 0 0 0)
			(layer "F.SilkS")
			(hide yes)
			(effects
				(font
					(size 1.27 1.27)
				)
			)
		)
		(property "Value" "0R2J-2-GP"
			(at 0.064008 -3.993896 0)
			(unlocked yes)
			(layer "F.Fab")
			(hide yes)
			(effects
				(font
					(size 1.016 1.016)
					(thickness 0.1524)
				)
			)
		)
		(property "Device Type" "R402H16"
			(at 0.064008 -5.517896 0)
			(unlocked yes)
			(layer "F.Fab")
			(hide yes)
			(effects
				(font
					(size 1.016 1.016)
					(thickness 0.1524)
				)
			)
		)
		(duplicate_pad_numbers_are_jumpers no)
		(fp_line
			(start -0.508 -0.9398)
			(end -0.508 0.9398)
			(stroke
				(width 0.1524)
				(type default)
			)
			(layer "F.SilkS")
		)
		(fp_line
			(start 0.508 -0.9398)
			(end -0.508 -0.9398)
			(stroke
				(width 0.1524)
				(type default)
			)
			(layer "F.SilkS")
		)
		(fp_rect
			(start -0.508 0.9398)
			(end 0.508 -0.9398)
			(stroke
				(width 0)
				(type default)
			)
			(fill no)
			(layer "F.CrtYd")
		)
		(fp_rect
			(start -0.508 0.9398)
			(end 0.508 -0.9398)
			(stroke
				(width 0)
				(type default)
			)
			(fill no)
			(layer "F.Fab")
		)
		(pad "1" smd custom
			(at 0 -0.4445)
			(size 0.1397 0.1397)
			(layers "F.Cu" "F.Mask" "F.Paste")
			(net "OTP_RETRY_DIODE")
			(options
				(clearance outline)
				(anchor circle)
			)
			(primitives
				(gr_poly
					(pts
						(arc
							(start -0.1778 -0.2794)
							(mid -0.249642 -0.249642)
							(end -0.2794 -0.1778)
						)
						(arc
							(start -0.2794 0.1778)
							(mid -0.249642 0.249642)
							(end -0.1778 0.2794)
						)
						(arc
							(start 0.1778 0.2794)
							(mid 0.249642 0.249642)
							(end 0.2794 0.1778)
						)
						(arc
							(start 0.2794 -0.1778)
							(mid 0.249642 -0.249642)
							(end 0.1778 -0.2794)
						)
					)
					(width 0)
					(fill yes)
				)
			)
		)
		(pad "2" smd custom
			(at 0 0.4445)
			(size 0.1397 0.1397)
			(layers "F.Cu" "F.Mask" "F.Paste")
			(net "OTP_RETRY_G")
			(options
				(clearance outline)
				(anchor circle)
			)
			(primitives
				(gr_poly
					(pts
						(arc
							(start -0.1778 -0.2794)
							(mid -0.249642 -0.249642)
							(end -0.2794 -0.1778)
						)
						(arc
							(start -0.2794 0.1778)
							(mid -0.249642 0.249642)
							(end -0.1778 0.2794)
						)
						(arc
							(start 0.1778 0.2794)
							(mid 0.249642 0.249642)
							(end 0.2794 0.1778)
						)
						(arc
							(start 0.2794 -0.1778)
							(mid 0.249642 -0.249642)
							(end 0.1778 -0.2794)
						)
					)
					(width 0)
					(fill yes)
				)
			)
		)
	)
	(footprint ""
		(layer "F.Cu")
		(at 39.243 -149.098 -90)
		(property "Reference" "PR108"
			(at 0 0 270)
			(layer "F.SilkS")
			(hide yes)
			(effects
				(font
					(size 1.27 1.27)
				)
			)
		)
		(property "Value" "6K81R2F-1-GP"
			(at 0.064008 -3.993896 270)
			(unlocked yes)
			(layer "F.Fab")
			(hide yes)
			(effects
				(font
					(size 1.016 1.016)
					(thickness 0.1524)
				)
			)
		)
		(property "Device Type" "R402H16"
			(at 0.064008 -5.517896 270)
			(unlocked yes)
			(layer "F.Fab")
			(hide yes)
			(effects
				(font
					(size 1.016 1.016)
					(thickness 0.1524)
				)
			)
		)
		(duplicate_pad_numbers_are_jumpers no)
		(fp_line
			(start -0.508 -0.9398)
			(end -0.508 0.9398)
			(stroke
				(width 0.1524)
				(type default)
			)
			(layer "F.SilkS")
		)
		(fp_line
			(start 0.508 -0.9398)
			(end -0.508 -0.9398)
			(stroke
				(width 0.1524)
				(type default)
			)
			(layer "F.SilkS")
		)
		(fp_rect
			(start -0.508 0.9398)
			(end 0.508 -0.9398)
			(stroke
				(width 0)
				(type default)
			)
			(fill no)
			(layer "F.CrtYd")
		)
		(fp_rect
			(start -0.508 0.9398)
			(end 0.508 -0.9398)
			(stroke
				(width 0)
				(type default)
			)
			(fill no)
			(layer "F.Fab")
		)
		(pad "1" smd custom
			(at 0 -0.4445 270)
			(size 0.1397 0.1397)
			(layers "F.Cu" "F.Mask" "F.Paste")
			(net "P12V")
			(options
				(clearance outline)
				(anchor circle)
			)
			(primitives
				(gr_poly
					(pts
						(arc
							(start -0.1778 -0.2794)
							(mid -0.249642 -0.249642)
							(end -0.2794 -0.1778)
						)
						(arc
							(start -0.2794 0.1778)
							(mid -0.249642 0.249642)
							(end -0.1778 0.2794)
						)
						(arc
							(start 0.1778 0.2794)
							(mid 0.249642 0.249642)
							(end 0.2794 0.1778)
						)
						(arc
							(start 0.2794 -0.1778)
							(mid 0.249642 -0.249642)
							(end 0.1778 -0.2794)
						)
					)
					(width 0)
					(fill yes)
				)
			)
		)
		(pad "2" smd custom
			(at 0 0.4445 270)
			(size 0.1397 0.1397)
			(layers "F.Cu" "F.Mask" "F.Paste")
			(net "P12VU_2490_EN_1")
			(options
				(clearance outline)
				(anchor circle)
			)
			(primitives
				(gr_poly
					(pts
						(arc
							(start -0.1778 -0.2794)
							(mid -0.249642 -0.249642)
							(end -0.2794 -0.1778)
						)
						(arc
							(start -0.2794 0.1778)
							(mid -0.249642 0.249642)
							(end -0.1778 0.2794)
						)
						(arc
							(start 0.1778 0.2794)
							(mid 0.249642 0.249642)
							(end 0.2794 0.1778)
						)
						(arc
							(start 0.2794 -0.1778)
							(mid 0.249642 -0.249642)
							(end 0.1778 -0.2794)
						)
					)
					(width 0)
					(fill yes)
				)
			)
		)
	)
	(footprint ""
		(layer "F.Cu")
		(at 20.6756 -135.1788)
		(property "Reference" "PR95"
			(at 0 0 0)
			(layer "F.SilkS")
			(hide yes)
			(effects
				(font
					(size 1.27 1.27)
				)
			)
		)
		(property "Value" "0R2J-2-GP"
			(at 0.064008 -3.993896 0)
			(unlocked yes)
			(layer "F.Fab")
			(hide yes)
			(effects
				(font
					(size 1.016 1.016)
					(thickness 0.1524)
				)
			)
		)
		(property "Device Type" "R402H16"
			(at 0.064008 -5.517896 0)
			(unlocked yes)
			(layer "F.Fab")
			(hide yes)
			(effects
				(font
					(size 1.016 1.016)
					(thickness 0.1524)
				)
			)
		)
		(duplicate_pad_numbers_are_jumpers no)
		(fp_line
			(start -0.508 -0.9398)
			(end -0.508 0.9398)
			(stroke
				(width 0.1524)
				(type default)
			)
			(layer "F.SilkS")
		)
		(fp_line
			(start 0.508 -0.9398)
			(end -0.508 -0.9398)
			(stroke
				(width 0.1524)
				(type default)
			)
			(layer "F.SilkS")
		)
		(fp_rect
			(start -0.508 0.9398)
			(end 0.508 -0.9398)
			(stroke
				(width 0)
				(type default)
			)
			(fill no)
			(layer "F.CrtYd")
		)
		(fp_rect
			(start -0.508 0.9398)
			(end 0.508 -0.9398)
			(stroke
				(width 0)
				(type default)
			)
			(fill no)
			(layer "F.Fab")
		)
		(pad "1" smd custom
			(at 0 -0.4445)
			(size 0.1397 0.1397)
			(layers "F.Cu" "F.Mask" "F.Paste")
			(net "P12VU_2490_SENSE")
			(options
				(clearance outline)
				(anchor circle)
			)
			(primitives
				(gr_poly
					(pts
						(arc
							(start -0.1778 -0.2794)
							(mid -0.249642 -0.249642)
							(end -0.2794 -0.1778)
						)
						(arc
							(start -0.2794 0.1778)
							(mid -0.249642 0.249642)
							(end -0.1778 0.2794)
						)
						(arc
							(start 0.1778 0.2794)
							(mid 0.249642 0.249642)
							(end 0.2794 0.1778)
						)
						(arc
							(start 0.2794 -0.1778)
							(mid 0.249642 -0.249642)
							(end 0.1778 -0.2794)
						)
					)
					(width 0)
					(fill yes)
				)
			)
		)
		(pad "2" smd custom
			(at 0 0.4445)
			(size 0.1397 0.1397)
			(layers "F.Cu" "F.Mask" "F.Paste")
			(net "P12VU_NET")
			(options
				(clearance outline)
				(anchor circle)
			)
			(primitives
				(gr_poly
					(pts
						(arc
							(start -0.1778 -0.2794)
							(mid -0.249642 -0.249642)
							(end -0.2794 -0.1778)
						)
						(arc
							(start -0.2794 0.1778)
							(mid -0.249642 0.249642)
							(end -0.1778 0.2794)
						)
						(arc
							(start 0.1778 0.2794)
							(mid 0.249642 0.249642)
							(end 0.2794 0.1778)
						)
						(arc
							(start 0.2794 -0.1778)
							(mid 0.249642 -0.249642)
							(end 0.1778 -0.2794)
						)
					)
					(width 0)
					(fill yes)
				)
			)
		)
	)
)
